# T6G (Grand Teton) — schematic netlist excerpt (pin names and nets, part order shuffled) for the footprints in the layout excerpt that follows; sources: Cadence DE-HDL packaged netlist, KiCad conversion of 04192023_DAF0TMB3IC0_F0TG_MB_C_brd_V02_OCP.brd

J23  SCONN288_DDR506112002KQ  IO  pkg DDR288S_1-1VXC  page 91
  VIN_BULK0  = P12V_MEM_CPU0
  RFU0  = NC
  VIN_MGMT  = P3V3_AUX
  HSCL  = I3C_SPD_DDRF_CPU0_SCL
  HSDA  = I3C_SPD_DDRF_CPU0_SDA
  VSS0  = GND
  DQ0_A  = M_F_CPU0_SA_DQ<0>
  VSS1  = GND
  DQ1_A  = M_F_CPU0_SA_DQ<1>
  VSS2  = GND
  DQS0_A_T  = M_F_CPU0_SA_DQS_DP<0>
  DQS0_A_C  = M_F_CPU0_SA_DQS_DN<0>
  VSS3  = GND
  DQ4_A  = M_F_CPU0_SA_DQ<4>
  VSS4  = GND
  DQ5_A  = M_F_CPU0_SA_DQ<5>
  VSS5  = GND
  DQ8_A  = M_F_CPU0_SA_DQ<8>
  VSS6  = GND
  DQ9_A  = M_F_CPU0_SA_DQ<9>
  VSS7  = GND
  DQS1_A_T  = M_F_CPU0_SA_DQS_DP<1>
  DQS1_A_C  = M_F_CPU0_SA_DQS_DN<1>
  VSS8  = GND
  DQ12_A  = M_F_CPU0_SA_DQ<12>
  VSS9  = GND
  DQ13_A  = M_F_CPU0_SA_DQ<13>
  VSS10  = GND
  DQ16_A  = M_F_CPU0_SA_DQ<16>
  VSS11  = GND
  DQ17_A  = M_F_CPU0_SA_DQ<17>
  VSS12  = GND
  DQS2_A_T  = M_F_CPU0_SA_DQS_DP<2>
  DQS2_A_C  = M_F_CPU0_SA_DQS_DN<2>
  VSS13  = GND
  DQ20_A  = M_F_CPU0_SA_DQ<20>
  VSS14  = GND
  DQ21_A  = M_F_CPU0_SA_DQ<21>
  VSS15  = GND
  DQ24_A  = M_F_CPU0_SA_DQ<24>
  VSS16  = GND
  DQ25_A  = M_F_CPU0_SA_DQ<25>
  VSS17  = GND
  DQS3_A_T  = M_F_CPU0_SA_DQS_DP<3>
  DQS3_A_C  = M_F_CPU0_SA_DQS_DN<3>
  VSS18  = GND
  DQ28_A  = M_F_CPU0_SA_DQ<28>
  VSS19  = GND
  DQ29_A  = M_F_CPU0_SA_DQ<29>
  VSS20  = GND
  CB0_A  = M_F_CPU0_SA_CB<0>
  VSS21  = GND
  CB1_A  = M_F_CPU0_SA_CB<1>
  VSS22  = GND
  DQS4_A_T  = M_F_CPU0_SA_DQS_DP<4>
  DQS4_A_C  = M_F_CPU0_SA_DQS_DN<4>
  VSS23  = GND
  CB4_A  = M_F_CPU0_SA_CB<4>
  VSS24  = GND
  CB5_A  = M_F_CPU0_SA_CB<5>
  VSS25  = GND
  ALERT_N  = M_F_CPU0_ALERT_N
  VSS26  = GND
  CS0_A_N  = M_F_CPU0_SA_CS_N<0>
  VSS27  = GND
  CA0_A  = M_F_CPU0_SA_CA<0>
  VSS28  = GND
  CA2_A  = M_F_CPU0_SA_CA<2>
  VSS29  = GND
  CA4_A  = M_F_CPU0_SA_CA<4>
  VSS30  = GND
  CA6_A  = M_F_CPU0_SA_CA<6>
  VSS31  = GND
  PAR_A  = M_F_CPU0_SA_PAR
  VSS32  = GND
  CA0_B  = M_F_CPU0_SB_CA<0>
  VSS33  = GND
  CA2_B  = M_F_CPU0_SB_CA<2>
  VSS34  = GND
  CA4_B  = M_F_CPU0_SB_CA<4>
  VSS35  = GND
  CA6_B  = M_F_CPU0_SB_CA<6>
  VSS36  = GND
  CS0_B_N  = M_F_CPU0_SB_CS_N<0>
  VSS37  = GND
  \lbd||rsp_a_n\  = M_F_CPU0_SA_RSP<0>
  \lbs||rsp_b_n\  = M_F_CPU0_SB_RSP<0>
  VSS38  = GND
  CB4_B  = M_F_CPU0_SB_CB<4>
  VSS39  = GND
  CB5_B  = M_F_CPU0_SB_CB<5>
  VSS40  = GND
  \dqs9_b_t||tdqs9_b_t||dbi4_b_n\  = M_F_CPU0_SB_DQS_DP<9>
  \dqs9_b_c||tdqs9_b_c\  = M_F_CPU0_SB_DQS_DN<9>
  VSS41  = GND
  CB0_B  = M_F_CPU0_SB_CB<0>
  VSS42  = GND
  CB1_B  = M_F_CPU0_SB_CB<1>
  VSS43  = GND
  DQ0_B  = M_F_CPU0_SB_DQ<0>
  VSS44  = GND
  DQ1_B  = M_F_CPU0_SB_DQ<1>
  VSS45  = GND
  DQS0_B_T  = M_F_CPU0_SB_DQS_DP<0>
  DQS0_B_C  = M_F_CPU0_SB_DQS_DN<0>
  VSS46  = GND
  DQ4_B  = M_F_CPU0_SB_DQ<4>
  VSS47  = GND
  DQ5_B  = M_F_CPU0_SB_DQ<5>
  VSS48  = GND
  DQ8_B  = M_F_CPU0_SB_DQ<8>
  VSS49  = GND
  DQ9_B  = M_F_CPU0_SB_DQ<9>
  VSS50  = GND
  DQS1_B_T  = M_F_CPU0_SB_DQS_DP<1>
  DQS1_B_C  = M_F_CPU0_SB_DQS_DN<1>
  VSS51  = GND
  DQ12_B  = M_F_CPU0_SB_DQ<12>
  VSS52  = GND
  DQ13_B  = M_F_CPU0_SB_DQ<13>
  VSS53  = GND
  DQ16_B  = M_F_CPU0_SB_DQ<16>
  VSS54  = GND
  DQ17_B  = M_F_CPU0_SB_DQ<17>
  VSS55  = GND
  DQS2_B_T  = M_F_CPU0_SB_DQS_DP<2>
  DQS2_B_C  = M_F_CPU0_SB_DQS_DN<2>
  VSS56  = GND
  DQ20_B  = M_F_CPU0_SB_DQ<20>
  VSS57  = GND
  DQ21_B  = M_F_CPU0_SB_DQ<21>
  VSS58  = GND
  DQ24_B  = M_F_CPU0_SB_DQ<24>
  VSS59  = GND
  DQ25_B  = M_F_CPU0_SB_DQ<25>
  VSS60  = GND
  DQS3_B_T  = M_F_CPU0_SB_DQS_DP<3>
  DQS3_B_C  = M_F_CPU0_SB_DQS_DN<3>
  VSS61  = GND
  DQ28_B  = M_F_CPU0_SB_DQ<28>
  VSS62  = GND
  DQ29_B  = M_F_CPU0_SB_DQ<29>
  VSS63  = GND
  RFU1  = NC
  VIN_BULK1  = P12V_MEM_CPU0
  VIN_BULK2  = P12V_MEM_CPU0
  \pwr_good||fail_n\  = PWRGD_CHF_CPU0_DIMM
  HAS  = PD_CHF_CPU0_DIMM_SAA
  RFU2  = NC
  RFU3  = NC
  VSS64  = GND
  DQ2_A  = M_F_CPU0_SA_DQ<2>
  VSS65  = GND
  DQ3_A  = M_F_CPU0_SA_DQ<3>
  VSS66  = GND
  \dqs5_a_c||tdqs5_a_c||dqs5_a_t||tdqs5_a_t\  = M_F_CPU0_SA_DQS_DN<5>
  \dqs5_a_t||tdqs5_a_t\  = M_F_CPU0_SA_DQS_DP<5>
  VSS67  = GND
  DQ6_A  = M_F_CPU0_SA_DQ<6>
  VSS68  = GND
  DQ7_A  = M_F_CPU0_SA_DQ<7>
  VSS69  = GND
  DQ10_A  = M_F_CPU0_SA_DQ<10>
  VSS70  = GND
  DQ11_A  = M_F_CPU0_SA_DQ<11>
  VSS71  = GND
  \dqs6_a_c||tdqs6_a_c||dqs6_a_t||tdqs6_a_t\  = M_F_CPU0_SA_DQS_DN<6>
  \dqs6_a_t||tdqs6_a_t\  = M_F_CPU0_SA_DQS_DP<6>
  VSS72  = GND
  DQ14_A  = M_F_CPU0_SA_DQ<14>
  VSS73  = GND
  DQ15_A  = M_F_CPU0_SA_DQ<15>
  VSS74  = GND
  DQ18_A  = M_F_CPU0_SA_DQ<18>
  VSS75  = GND
  DQ19_A  = M_F_CPU0_SA_DQ<19>
  VSS76  = GND
  \dqs7_a_c||tdqs7_a_c\  = M_F_CPU0_SA_DQS_DN<7>
  \dqs7_a_t||tdqs7_a_t\  = M_F_CPU0_SA_DQS_DP<7>
  VSS77  = GND
  DQ22_A  = M_F_CPU0_SA_DQ<22>
  VSS78  = GND
  DQ23_A  = M_F_CPU0_SA_DQ<23>
  VSS79  = GND
  DQ26_A  = M_F_CPU0_SA_DQ<26>
  VSS80  = GND
  DQ27_A  = M_F_CPU0_SA_DQ<27>
  VSS81  = GND
  \dqs8_a_c||tdqs8_a_c\  = M_F_CPU0_SA_DQS_DN<8>
  \dqs8_a_t||tdqs8_a_t\  = M_F_CPU0_SA_DQS_DP<8>
  VSS82  = GND
  DQ30_A  = M_F_CPU0_SA_DQ<30>
  VSS83  = GND
  DQ31_A  = M_F_CPU0_SA_DQ<31>
  VSS84  = GND
  CB2_A  = M_F_CPU0_SA_CB<2>
  VSS85  = GND
  CB3_A  = M_F_CPU0_SA_CB<3>
  VSS86  = GND
  \dqs9_a_c||tdqs9_a_c\  = M_F_CPU0_SA_DQS_DN<9>
  \dqs9_a_t||tdqs9_a_t\  = M_F_CPU0_SA_DQS_DP<9>
  VSS87  = GND
  CB6_A  = M_F_CPU0_SA_CB<6>
  VSS88  = GND
  CB7_A  = M_F_CPU0_SA_CB<7>
  VSS89  = GND
  RESET_N  = M_F_CPU0_RESET_N
  VSS90  = GND
  CS1_A_N  = M_F_CPU0_SA_CS_N<1>
  VSS91  = GND
  CA1_A  = M_F_CPU0_SA_CA<1>
  VSS92  = GND
  CA3_A  = M_F_CPU0_SA_CA<3>
  VSS93  = GND
  CA5_A  = M_F_CPU0_SA_CA<5>
  VSS94  = GND
  CK_T  = M_F_CPU0_CLK_DP<0>
  CK_C  = M_F_CPU0_CLK_DN<0>
  VSS95  = GND
  RFU4  = NC
  CA1_B  = M_F_CPU0_SB_CA<1>
  VSS96  = GND
  CA3_B  = M_F_CPU0_SB_CA<3>
  VSS97  = GND
  CA5_B  = M_F_CPU0_SB_CA<5>
  VSS98  = GND
  PAR_B  = M_F_CPU0_SB_PAR
  VSS99  = GND
  CS1_B_N  = M_F_CPU0_SB_CS_N<1>
  VSS100  = GND
  RFU5  = NC
  RFU6  = NC
  VSS101  = GND
  CB6_B  = M_F_CPU0_SB_CB<6>
  VSS102  = GND
  CB7_B  = M_F_CPU0_SB_CB<7>
  VSS103  = GND
  DQS4_B_C  = M_F_CPU0_SB_DQS_DN<4>
  DQS4_B_T  = M_F_CPU0_SB_DQS_DP<4>
  VSS104  = GND
  CB2_B  = M_F_CPU0_SB_CB<2>
  VSS105  = GND
  CB3_B  = M_F_CPU0_SB_CB<3>
  VSS106  = GND
  DQ2_B  = M_F_CPU0_SB_DQ<2>
  VSS107  = GND
  DQ3_B  = M_F_CPU0_SB_DQ<3>
  VSS108  = GND
  \dqs5_b_c||tdqs5_b_c\  = M_F_CPU0_SB_DQS_DN<5>
  \dqs5_b_t||tdqs5_b_t\  = M_F_CPU0_SB_DQS_DP<5>
  VSS109  = GND
  DQ6_B  = M_F_CPU0_SB_DQ<6>
  VSS110  = GND
  DQ7_B  = M_F_CPU0_SB_DQ<7>
  VSS111  = GND
  DQ10_B  = M_F_CPU0_SB_DQ<10>
  VSS112  = GND
  DQ11_B  = M_F_CPU0_SB_DQ<11>
  VSS113  = GND
  \dqs6_b_c||tdqs6_b_c\  = M_F_CPU0_SB_DQS_DN<6>
  \dqs6_b_t||tdqs6_b_t\  = M_F_CPU0_SB_DQS_DP<6>
  VSS114  = GND
  DQ14_B  = M_F_CPU0_SB_DQ<14>
  VSS115  = GND
  DQ15_B  = M_F_CPU0_SB_DQ<15>
  VSS116  = GND
  DQ18_B  = M_F_CPU0_SB_DQ<18>
  VSS117  = GND
  DQ19_B  = M_F_CPU0_SB_DQ<19>
  VSS118  = GND
  \dqs7_b_c||tdqs7_b_c\  = M_F_CPU0_SB_DQS_DN<7>
  \dqs7_b_t||tdqs7_b_t\  = M_F_CPU0_SB_DQS_DP<7>
  VSS119  = GND
  DQ22_B  = M_F_CPU0_SB_DQ<22>
  VSS120  = GND
  DQ23_B  = M_F_CPU0_SB_DQ<23>
  VSS121  = GND
  DQ26_B  = M_F_CPU0_SB_DQ<26>
  VSS122  = GND
  DQ27_B  = M_F_CPU0_SB_DQ<27>
  VSS123  = GND
  \dqs8_b_c||tdqs8_b_c\  = M_F_CPU0_SB_DQS_DN<8>
  \dqs8_b_t||tdqs8_b_t\  = M_F_CPU0_SB_DQS_DP<8>
  VSS124  = GND
  DQ30_B  = M_F_CPU0_SB_DQ<30>
  VSS125  = GND
  DQ31_B  = M_F_CPU0_SB_DQ<31>
  VSS126  = GND
  G1  = GND
  G2  = GND
  G3  = GND

(kicad_pcb
	(version 20260206)
	(generator "pcbnew")
	(generator_version "10.0")
	(general
		(thickness 1.6)
		(legacy_teardrops no)
	)
	(paper "A4")
	(title_block
		(title "04192023_DAF0TMB3IC0_F0TG_MB_C_brd_V02_OCP.brd")
		(comment 1 "Grand Teton / footprint 2449 of 8354 (J23), pads 93-138 of 291")
	)
	(layers
		(0 "F.Cu" signal "TOP")
		(4 "In1.Cu" signal "GND")
		(6 "In2.Cu" signal "IN1")
		(8 "In3.Cu" signal "GND1")
		(10 "In4.Cu" signal "IN2")
		(12 "In5.Cu" signal "GND2")
		(14 "In6.Cu" signal "IN3")
		(16 "In7.Cu" signal "GND3")
		(18 "In8.Cu" signal "VCC")
		(20 "In9.Cu" signal "VCC1")
		(22 "In10.Cu" signal "GND4")
		(24 "In11.Cu" signal "IN4")
		(26 "In12.Cu" signal "GND5")
		(28 "In13.Cu" signal "IN5")
		(30 "In14.Cu" signal "GND6")
		(32 "In15.Cu" signal "IN6")
		(34 "In16.Cu" signal "GND7")
		(2 "B.Cu" signal "BOTTOM")
		(9 "F.Adhes" user "F.Adhesive")
		(11 "B.Adhes" user "B.Adhesive")
		(13 "F.Paste" user "Package Geometry/Pastemask Top")
		(15 "B.Paste" user "Package Geometry/Pastemask Bottom")
		(5 "F.SilkS" user "Ref Des/Silkscreen Top")
		(7 "B.SilkS" user "Ref Des/Silkscreen Bottom")
		(1 "F.Mask" user "Board Geometry/Soldermask Top")
		(3 "B.Mask" user "Board Geometry/Soldermask Bottom")
		(17 "Dwgs.User" user "User.Drawings")
		(19 "Cmts.User" user "User.Comments")
		(21 "Eco1.User" user "User.Eco1")
		(23 "Eco2.User" user "User.Eco2")
		(25 "Edge.Cuts" user "Board Geometry/Outline")
		(27 "Margin" user)
		(31 "F.CrtYd" user "Package Geometry/Place Bound Top")
		(29 "B.CrtYd" user "Package Geometry/Place Bound Bottom")
		(35 "F.Fab" user "Ref Des/Assembly Top")
		(33 "B.Fab" user "Ref Des/Assembly Bottom")
	)
	(footprint ""
		(layer "F.Cu")
		(at 267.598144 -255.560068 180)
		(property "Reference" "J23"
			(at -2.2098 -81.984088 0)
			(unlocked yes)
			(layer "F.SilkS")
			(effects
				(font
					(size 0.7874 0.5842)
					(thickness 0.1524)
				)
			)
		)
		(property "Value" ""
			(at 0 0 180)
			(layer "F.Fab")
			(effects
				(font
					(size 1.27 1.27)
				)
			)
		)
		(duplicate_pad_numbers_are_jumpers no)
		(pad "93" smd rect
			(at -2.050034 19.975068 90)
			(size 0.519938 1.4986)
			(layers "F.Cu" "F.Mask" "F.Paste")
			(net "M_F_CPU0_SB_DQS_DP<9>")
		)
		(pad "94" smd rect
			(at -2.050034 20.824952 90)
			(size 0.519938 1.4986)
			(layers "F.Cu" "F.Mask" "F.Paste")
			(net "M_F_CPU0_SB_DQS_DN<9>")
		)
		(pad "95" smd rect
			(at -2.050034 21.67509 90)
			(size 0.519938 1.4986)
			(layers "F.Cu" "F.Mask" "F.Paste")
			(net "GND")
		)
		(pad "96" smd rect
			(at -2.050034 22.524974 90)
			(size 0.519938 1.4986)
			(layers "F.Cu" "F.Mask" "F.Paste")
			(net "M_F_CPU0_SB_CB<0>")
		)
		(pad "97" smd rect
			(at -2.050034 23.375112 90)
			(size 0.519938 1.4986)
			(layers "F.Cu" "F.Mask" "F.Paste")
			(net "GND")
		)
		(pad "98" smd rect
			(at -2.050034 24.224996 90)
			(size 0.519938 1.4986)
			(layers "F.Cu" "F.Mask" "F.Paste")
			(net "M_F_CPU0_SB_CB<1>")
		)
		(pad "99" smd rect
			(at -2.050034 25.07488 90)
			(size 0.519938 1.4986)
			(layers "F.Cu" "F.Mask" "F.Paste")
			(net "GND")
		)
		(pad "100" smd rect
			(at -2.050034 25.925018 90)
			(size 0.519938 1.4986)
			(layers "F.Cu" "F.Mask" "F.Paste")
			(net "M_F_CPU0_SB_DQ<0>")
		)
		(pad "101" smd rect
			(at -2.050034 26.774902 90)
			(size 0.519938 1.4986)
			(layers "F.Cu" "F.Mask" "F.Paste")
			(net "GND")
		)
		(pad "102" smd rect
			(at -2.050034 27.62504 90)
			(size 0.519938 1.4986)
			(layers "F.Cu" "F.Mask" "F.Paste")
			(net "M_F_CPU0_SB_DQ<1>")
		)
		(pad "103" smd rect
			(at -2.050034 28.474924 90)
			(size 0.519938 1.4986)
			(layers "F.Cu" "F.Mask" "F.Paste")
			(net "GND")
		)
		(pad "104" smd rect
			(at -2.050034 29.325062 90)
			(size 0.519938 1.4986)
			(layers "F.Cu" "F.Mask" "F.Paste")
			(net "M_F_CPU0_SB_DQS_DP<0>")
		)
		(pad "105" smd rect
			(at -2.050034 30.174946 90)
			(size 0.519938 1.4986)
			(layers "F.Cu" "F.Mask" "F.Paste")
			(net "M_F_CPU0_SB_DQS_DN<0>")
		)
		(pad "106" smd rect
			(at -2.050034 31.025084 90)
			(size 0.519938 1.4986)
			(layers "F.Cu" "F.Mask" "F.Paste")
			(net "GND")
		)
		(pad "107" smd rect
			(at -2.050034 31.874968 90)
			(size 0.519938 1.4986)
			(layers "F.Cu" "F.Mask" "F.Paste")
			(net "M_F_CPU0_SB_DQ<4>")
		)
		(pad "108" smd rect
			(at -2.050034 32.725106 90)
			(size 0.519938 1.4986)
			(layers "F.Cu" "F.Mask" "F.Paste")
			(net "GND")
		)
		(pad "109" smd rect
			(at -2.050034 33.57499 90)
			(size 0.519938 1.4986)
			(layers "F.Cu" "F.Mask" "F.Paste")
			(net "M_F_CPU0_SB_DQ<5>")
		)
		(pad "110" smd rect
			(at -2.050034 34.425128 90)
			(size 0.519938 1.4986)
			(layers "F.Cu" "F.Mask" "F.Paste")
			(net "GND")
		)
		(pad "111" smd rect
			(at -2.050034 35.275012 90)
			(size 0.519938 1.4986)
			(layers "F.Cu" "F.Mask" "F.Paste")
			(net "M_F_CPU0_SB_DQ<8>")
		)
		(pad "112" smd rect
			(at -2.050034 36.124896 90)
			(size 0.519938 1.4986)
			(layers "F.Cu" "F.Mask" "F.Paste")
			(net "GND")
		)
		(pad "113" smd rect
			(at -2.050034 36.975034 90)
			(size 0.519938 1.4986)
			(layers "F.Cu" "F.Mask" "F.Paste")
			(net "M_F_CPU0_SB_DQ<9>")
		)
		(pad "114" smd rect
			(at -2.050034 37.824918 90)
			(size 0.519938 1.4986)
			(layers "F.Cu" "F.Mask" "F.Paste")
			(net "GND")
		)
		(pad "115" smd rect
			(at -2.050034 38.675056 90)
			(size 0.519938 1.4986)
			(layers "F.Cu" "F.Mask" "F.Paste")
			(net "M_F_CPU0_SB_DQS_DP<1>")
		)
		(pad "116" smd rect
			(at -2.050034 39.52494 90)
			(size 0.519938 1.4986)
			(layers "F.Cu" "F.Mask" "F.Paste")
			(net "M_F_CPU0_SB_DQS_DN<1>")
		)
		(pad "117" smd rect
			(at -2.050034 40.375078 90)
			(size 0.519938 1.4986)
			(layers "F.Cu" "F.Mask" "F.Paste")
			(net "GND")
		)
		(pad "118" smd rect
			(at -2.050034 41.224962 90)
			(size 0.519938 1.4986)
			(layers "F.Cu" "F.Mask" "F.Paste")
			(net "M_F_CPU0_SB_DQ<12>")
		)
		(pad "119" smd rect
			(at -2.050034 42.0751 90)
			(size 0.519938 1.4986)
			(layers "F.Cu" "F.Mask" "F.Paste")
			(net "GND")
		)
		(pad "120" smd rect
			(at -2.050034 42.924984 90)
			(size 0.519938 1.4986)
			(layers "F.Cu" "F.Mask" "F.Paste")
			(net "M_F_CPU0_SB_DQ<13>")
		)
		(pad "121" smd rect
			(at -2.050034 43.775122 90)
			(size 0.519938 1.4986)
			(layers "F.Cu" "F.Mask" "F.Paste")
			(net "GND")
		)
		(pad "122" smd rect
			(at -2.050034 44.625006 90)
			(size 0.519938 1.4986)
			(layers "F.Cu" "F.Mask" "F.Paste")
			(net "M_F_CPU0_SB_DQ<16>")
		)
		(pad "123" smd rect
			(at -2.050034 45.47489 90)
			(size 0.519938 1.4986)
			(layers "F.Cu" "F.Mask" "F.Paste")
			(net "GND")
		)
		(pad "124" smd rect
			(at -2.050034 46.325028 90)
			(size 0.519938 1.4986)
			(layers "F.Cu" "F.Mask" "F.Paste")
			(net "M_F_CPU0_SB_DQ<17>")
		)
		(pad "125" smd rect
			(at -2.050034 47.174912 90)
			(size 0.519938 1.4986)
			(layers "F.Cu" "F.Mask" "F.Paste")
			(net "GND")
		)
		(pad "126" smd rect
			(at -2.050034 48.02505 90)
			(size 0.519938 1.4986)
			(layers "F.Cu" "F.Mask" "F.Paste")
			(net "M_F_CPU0_SB_DQS_DP<2>")
		)
		(pad "127" smd rect
			(at -2.050034 48.874934 90)
			(size 0.519938 1.4986)
			(layers "F.Cu" "F.Mask" "F.Paste")
			(net "M_F_CPU0_SB_DQS_DN<2>")
		)
		(pad "128" smd rect
			(at -2.050034 49.725072 90)
			(size 0.519938 1.4986)
			(layers "F.Cu" "F.Mask" "F.Paste")
			(net "GND")
		)
		(pad "129" smd rect
			(at -2.050034 50.574956 90)
			(size 0.519938 1.4986)
			(layers "F.Cu" "F.Mask" "F.Paste")
			(net "M_F_CPU0_SB_DQ<20>")
		)
		(pad "130" smd rect
			(at -2.050034 51.425094 90)
			(size 0.519938 1.4986)
			(layers "F.Cu" "F.Mask" "F.Paste")
			(net "GND")
		)
		(pad "131" smd rect
			(at -2.050034 52.274978 90)
			(size 0.519938 1.4986)
			(layers "F.Cu" "F.Mask" "F.Paste")
			(net "M_F_CPU0_SB_DQ<21>")
		)
		(pad "132" smd rect
			(at -2.050034 53.125116 90)
			(size 0.519938 1.4986)
			(layers "F.Cu" "F.Mask" "F.Paste")
			(net "GND")
		)
		(pad "133" smd rect
			(at -2.050034 53.975 90)
			(size 0.519938 1.4986)
			(layers "F.Cu" "F.Mask" "F.Paste")
			(net "M_F_CPU0_SB_DQ<24>")
		)
		(pad "134" smd rect
			(at -2.050034 54.824884 90)
			(size 0.519938 1.4986)
			(layers "F.Cu" "F.Mask" "F.Paste")
			(net "GND")
		)
		(pad "135" smd rect
			(at -2.050034 55.675022 90)
			(size 0.519938 1.4986)
			(layers "F.Cu" "F.Mask" "F.Paste")
			(net "M_F_CPU0_SB_DQ<25>")
		)
		(pad "136" smd rect
			(at -2.050034 56.524906 90)
			(size 0.519938 1.4986)
			(layers "F.Cu" "F.Mask" "F.Paste")
			(net "GND")
		)
		(pad "137" smd rect
			(at -2.050034 57.375044 90)
			(size 0.519938 1.4986)
			(layers "F.Cu" "F.Mask" "F.Paste")
			(net "M_F_CPU0_SB_DQS_DP<3>")
		)
		(pad "138" smd rect
			(at -2.050034 58.224928 90)
			(size 0.519938 1.4986)
			(layers "F.Cu" "F.Mask" "F.Paste")
			(net "M_F_CPU0_SB_DQS_DN<3>")
		)
	)
)
